FILE_TYPE = CONNECTIVITY;
{Allegro Design Entry HDL 17.4-2019 S026 (4007227) 1/17/2022}
"PAGE_NUMBER" = 77;
0"NC";
1"GND\g";
2"GND\g";
3"GND\g";
4"GND\g";
5"GND\g";
6"GND\g";
7"PWRGD_CPU1_PWROK";
8"PWRGD_CPU0_PWROK";
9"PVDDCR_CPU0_P0_RESET_N";
10"PVDDCR_CPU1_P0_RESET_N";
11"P1V8_AUX\g";
12"P1V8_AUX\g";
13"PVDDCR_CPU0_P1_RESET_N";
14"PVDDCR_CPU1_P1_RESET_N";
%"Q_RES"
"2","(-5900,3950)","2","pure_quanta","I1";
;
LOCATION"R702"
$SEC"1"
CDS_SEC"1"
PACK_TYPE"0402LF"
VALUE"10K"
TOLERANCE"5%"
MATERIAL"EMPTY"
WATTAGE"1/16W"
CDS_LIB"pure_quanta"
PART_NUMBER"CS31002JB08";
"A"
$PN"1"8;
"B"
$PN"2"2;
%"UNIVERSAL_GND"
"1","(-4125,4375)","0","pure_quanta_power","I10";
;
CDS_LIB"pure_quanta_power"
HDL_POWER"GND";
"A"1;
%"Q_CAP"
"1","(-4125,4575)","0","pure_quanta","I11";
;
LOCATION"C223"
$SEC"1"
CDS_SEC"1"
MATERIAL"X7R"
TOLERANCE"10%"
PACK_TYPE"0402"
VOLTAGE"25V"
VALUE"0.1UF"
CDS_LIB"pure_quanta"
PART_NUMBER"CH4104K1B00";
"B"
$PN"2"1;
"A"
$PN"1"12;
%"UNIVERSAL_POWER"
"1","(-4200,4900)","2","pure_quanta_power","I12";
;
HDL_POWER"P1V8_AUX"
CDS_LIB"pure_quanta_power";
"A"12;
%"SN74LVC2G07DCKR"
"1","(-4675,4275)","0","pure_quanta","I15";
;
LOCATION"U29"
$SEC"1"
CDS_SEC"1"
MATERIAL"IC"
VALUE"SN74LVC2G07DCKR"
PACK_TYPE"SMLF"
NEEDS_NO_SIZE"TRUE"
CDS_LIB"pure_quanta"
PART_NUMBER"AL002G07006";
"VCC"
$PN"5"12;
"GND"
$PN"2"6;
"2Y"
$PN"4"10;
"1Y"
$PN"6"9;
"2A"
$PN"3"8;
"1A"
$PN"1"8;
%"Q_CAP"
"1","(-4075,2800)","0","pure_quanta","I19";
;
LOCATION"C224"
$SEC"1"
CDS_SEC"1"
MATERIAL"X7R"
TOLERANCE"10%"
VALUE"0.1UF"
VOLTAGE"25V"
PACK_TYPE"0402"
CDS_LIB"pure_quanta"
PART_NUMBER"CH4104K1B00";
"B"
$PN"2"3;
"A"
$PN"1"11;
%"GND"
"1","(-5900,3675)","0","pure_quanta_power","I2";
;
CDS_LIB"pure_quanta_power"
SIZE"1B"
BOM_COST"MEM"
HDL_POWER"GND";
"A<SIZE-1..0>\NAC"2;
%"UNIVERSAL_GND"
"1","(-4075,2600)","0","pure_quanta_power","I20";
;
CDS_LIB"pure_quanta_power"
HDL_POWER"GND";
"A"3;
%"SN74LVC2G07DCKR"
"1","(-4625,2500)","0","pure_quanta","I21";
;
LOCATION"U40"
$SEC"1"
CDS_SEC"1"
MATERIAL"IC"
VALUE"SN74LVC2G07DCKR"
PACK_TYPE"SMLF"
NEEDS_NO_SIZE"TRUE"
CDS_LIB"pure_quanta"
PART_NUMBER"AL002G07006";
"VCC"
$PN"5"11;
"GND"
$PN"2"4;
"2Y"
$PN"4"14;
"1Y"
$PN"6"13;
"2A"
$PN"3"7;
"1A"
$PN"1"7;
%"UNIVERSAL_GND"
"1","(-5050,2500)","5","pure_quanta_power","I22";
;
CDS_LIB"pure_quanta_power"
HDL_POWER"GND";
"A"4;
%"UNIVERSAL_POWER"
"1","(-4150,3125)","2","pure_quanta_power","I23";
;
HDL_POWER"P1V8_AUX"
CDS_LIB"pure_quanta_power";
"A"11;
%"Q_RES"
"2","(-5850,2175)","2","pure_quanta","I5";
;
LOCATION"R703"
$SEC"1"
CDS_SEC"1"
PACK_TYPE"0402LF"
VALUE"10K"
TOLERANCE"5%"
MATERIAL"EMPTY"
WATTAGE"1/16W"
CDS_LIB"pure_quanta"
PART_NUMBER"CS31002JB08";
"A"
$PN"1"7;
"B"
$PN"2"5;
%"GND"
"1","(-5850,1900)","0","pure_quanta_power","I6";
;
SIZE"1B"
BOM_COST"MEM"
CDS_LIB"pure_quanta_power"
HDL_POWER"GND";
"A<SIZE-1..0>\NAC"5;
%"UNIVERSAL_GND"
"1","(-5100,4275)","5","pure_quanta_power","I9";
;
CDS_LIB"pure_quanta_power"
HDL_POWER"GND";
"A"6;
END.
